# T6G (Grand Teton) — schematic netlist excerpt (pin names and nets, part order shuffled) for the footprints in the layout excerpt that follows; sources: Cadence DE-HDL packaged netlist, KiCad conversion of 04192023_DAF0TMB3IC0_F0TG_MB_C_brd_V02_OCP.brd

PL52  Q_INDUCTOR4P_14  150NH IND  pkg L_TLM117513Q-151QL_11X7-5XA  page 194
  \1\  = SW_PVDDCR_CPU0_P0_SW2
  \2\  = IND_CPU0_P0_CPL1
  \3\  = IND_CPU0_P0_CPL2
  \4\  = PVDDCR_CPU0_P0

PR125  Q_RES  0 5% CHIP  pkg 0402LF  page 207 : A = P12V_AUX ; B = PVDD11_S3_P0_VINSEN
C773  Q_CAP_DIFFBUS  DIFF BUS_0.22UF 6.3V 20% X6S  pkg C0201  page 66 : \1\ = P5E_CPU1_P2_TX_C_DP<0> ; \2\ = P5E_CPU1_P2_TX_DP<0>

(kicad_pcb
	(version 20260206)
	(generator "pcbnew")
	(generator_version "10.0")
	(general
		(thickness 1.6)
		(legacy_teardrops no)
	)
	(paper "A4")
	(title_block
		(title "04192023_DAF0TMB3IC0_F0TG_MB_C_brd_V02_OCP.brd")
		(comment 1 "Grand Teton / footprints 1201-1203 of 8354")
	)
	(layers
		(0 "F.Cu" signal "TOP")
		(4 "In1.Cu" signal "GND")
		(6 "In2.Cu" signal "IN1")
		(8 "In3.Cu" signal "GND1")
		(10 "In4.Cu" signal "IN2")
		(12 "In5.Cu" signal "GND2")
		(14 "In6.Cu" signal "IN3")
		(16 "In7.Cu" signal "GND3")
		(18 "In8.Cu" signal "VCC")
		(20 "In9.Cu" signal "VCC1")
		(22 "In10.Cu" signal "GND4")
		(24 "In11.Cu" signal "IN4")
		(26 "In12.Cu" signal "GND5")
		(28 "In13.Cu" signal "IN5")
		(30 "In14.Cu" signal "GND6")
		(32 "In15.Cu" signal "IN6")
		(34 "In16.Cu" signal "GND7")
		(2 "B.Cu" signal "BOTTOM")
		(9 "F.Adhes" user "F.Adhesive")
		(11 "B.Adhes" user "B.Adhesive")
		(13 "F.Paste" user "Package Geometry/Pastemask Top")
		(15 "B.Paste" user "Package Geometry/Pastemask Bottom")
		(5 "F.SilkS" user "Ref Des/Silkscreen Top")
		(7 "B.SilkS" user "Ref Des/Silkscreen Bottom")
		(1 "F.Mask" user "Board Geometry/Soldermask Top")
		(3 "B.Mask" user "Board Geometry/Soldermask Bottom")
		(17 "Dwgs.User" user "User.Drawings")
		(19 "Cmts.User" user "User.Comments")
		(21 "Eco1.User" user "User.Eco1")
		(23 "Eco2.User" user "User.Eco2")
		(25 "Edge.Cuts" user "Board Geometry/Outline")
		(27 "Margin" user)
		(31 "F.CrtYd" user "Package Geometry/Place Bound Top")
		(29 "B.CrtYd" user "Package Geometry/Place Bound Bottom")
		(35 "F.Fab" user "Ref Des/Assembly Top")
		(33 "B.Fab" user "Ref Des/Assembly Bottom")
	)
	(footprint ""
		(layer "F.Cu")
		(at 372.557294 -192.061084 180)
		(property "Reference" "PL52"
			(at 4.468876 2.638806 90)
			(unlocked yes)
			(layer "F.SilkS")
			(effects
				(font
					(size 0.7874 0.5842)
					(thickness 0.1524)
				)
				(justify left)
			)
		)
		(property "Value" ""
			(at 0 0 180)
			(layer "F.Fab")
			(effects
				(font
					(size 1.27 1.27)
				)
			)
		)
		(duplicate_pad_numbers_are_jumpers no)
		(fp_line
			(start 3.750056 5.500116)
			(end 3.750056 -5.500116)
			(stroke
				(width 0.1524)
				(type default)
			)
			(layer "F.SilkS")
		)
		(fp_line
			(start 3.750056 -5.500116)
			(end 2.393442 -5.500116)
			(stroke
				(width 0.1524)
				(type default)
			)
			(layer "F.SilkS")
		)
		(fp_line
			(start 2.393442 5.500116)
			(end 3.750056 5.500116)
			(stroke
				(width 0.1524)
				(type default)
			)
			(layer "F.SilkS")
		)
		(fp_line
			(start -2.393442 5.500116)
			(end -3.750056 5.500116)
			(stroke
				(width 0.1524)
				(type default)
			)
			(layer "F.SilkS")
		)
		(fp_line
			(start -3.750056 5.500116)
			(end -3.750056 -5.500116)
			(stroke
				(width 0.1524)
				(type default)
			)
			(layer "F.SilkS")
		)
		(fp_line
			(start -3.750056 -5.500116)
			(end -2.393442 -5.500116)
			(stroke
				(width 0.1524)
				(type default)
			)
			(layer "F.SilkS")
		)
		(fp_poly
			(pts
				(xy -3.9116 -4.249928) (xy -4.505706 -3.952748) (xy -4.505706 -4.547108)
			)
			(stroke
				(width 0)
				(type default)
			)
			(fill yes)
			(layer "F.SilkS")
		)
		(fp_line
			(start 3.750056 5.500116)
			(end 3.750056 -5.500116)
			(stroke
				(width 0.1)
				(type default)
			)
			(layer "F.Fab")
		)
		(fp_line
			(start 3.750056 -5.500116)
			(end -3.750056 -5.500116)
			(stroke
				(width 0.1)
				(type default)
			)
			(layer "F.Fab")
		)
		(fp_line
			(start -3.750056 5.500116)
			(end 3.750056 5.500116)
			(stroke
				(width 0.1)
				(type default)
			)
			(layer "F.Fab")
		)
		(fp_line
			(start -3.750056 -5.500116)
			(end -3.750056 5.500116)
			(stroke
				(width 0.1)
				(type default)
			)
			(layer "F.Fab")
		)
		(fp_poly
			(pts
				(xy -4.9276 -4.757928) (xy -4.9276 -3.741928) (xy -3.9116 -4.249928)
			)
			(stroke
				(width 0)
				(type default)
			)
			(fill yes)
			(layer "F.Fab")
		)
		(pad "1" smd rect
			(at 0 -4.249928 90)
			(size 2.413 4.5212)
			(layers "F.Cu" "F.Mask" "F.Paste")
			(net "SW_PVDDCR_CPU0_P0_SW2")
		)
		(pad "2" smd rect
			(at 0 -1.175004 90)
			(size 1.3716 4.5212)
			(layers "F.Cu" "F.Mask" "F.Paste")
			(net "IND_CPU0_P0_CPL1")
		)
		(pad "3" smd rect
			(at 0 1.175004 90)
			(size 1.3716 4.5212)
			(layers "F.Cu" "F.Mask" "F.Paste")
			(net "IND_CPU0_P0_CPL2")
		)
		(pad "4" smd rect
			(at 0 4.249928 90)
			(size 2.413 4.5212)
			(layers "F.Cu" "F.Mask" "F.Paste")
			(net "PVDDCR_CPU0_P0")
		)
	)
	(footprint ""
		(layer "F.Cu")
		(at 142.595092 -382.39446 180)
		(property "Reference" "C773"
			(at 0 0 180)
			(layer "F.SilkS")
			(hide yes)
			(effects
				(font
					(size 1.27 1.27)
				)
			)
		)
		(property "Value" ""
			(at 0 0 180)
			(layer "F.Fab")
			(effects
				(font
					(size 1.27 1.27)
				)
			)
		)
		(duplicate_pad_numbers_are_jumpers no)
		(fp_line
			(start 0.299974 0.150114)
			(end -0.299974 0.150114)
			(stroke
				(width 0.1)
				(type default)
			)
			(layer "F.Fab")
		)
		(fp_line
			(start 0.299974 -0.150114)
			(end 0.299974 0.150114)
			(stroke
				(width 0.1)
				(type default)
			)
			(layer "F.Fab")
		)
		(fp_line
			(start -0.299974 0.150114)
			(end -0.299974 -0.150114)
			(stroke
				(width 0.1)
				(type default)
			)
			(layer "F.Fab")
		)
		(fp_line
			(start -0.299974 -0.150114)
			(end 0.299974 -0.150114)
			(stroke
				(width 0.1)
				(type default)
			)
			(layer "F.Fab")
		)
		(pad "1" smd rect
			(at -0.2667 0 180)
			(size 0.3048 0.381)
			(layers "F.Cu" "F.Mask" "F.Paste")
			(net "P5E_CPU1_P2_TX_C_DP<0>")
		)
		(pad "2" smd rect
			(at 0.2667 0 180)
			(size 0.3048 0.381)
			(layers "F.Cu" "F.Mask" "F.Paste")
			(net "P5E_CPU1_P2_TX_DP<0>")
		)
	)
	(footprint ""
		(layer "F.Cu")
		(at 426.974 -366.141 -90)
		(property "Reference" "PR125"
			(at 0 0 270)
			(layer "F.SilkS")
			(hide yes)
			(effects
				(font
					(size 1.27 1.27)
				)
			)
		)
		(property "Value" ""
			(at 0 0 270)
			(layer "F.Fab")
			(effects
				(font
					(size 1.27 1.27)
				)
			)
		)
		(duplicate_pad_numbers_are_jumpers no)
		(fp_line
			(start -0.7874 0.4064)
			(end -0.7874 -0.4064)
			(stroke
				(width 0.1524)
				(type default)
			)
			(layer "F.SilkS")
		)
		(fp_line
			(start 0.7874 0.4064)
			(end -0.7874 0.4064)
			(stroke
				(width 0.1524)
				(type default)
			)
			(layer "F.SilkS")
		)
		(fp_line
			(start -0.7874 -0.4064)
			(end 0.7874 -0.4064)
			(stroke
				(width 0.1524)
				(type default)
			)
			(layer "F.SilkS")
		)
		(fp_line
			(start 0.7874 -0.4064)
			(end 0.7874 0.4064)
			(stroke
				(width 0.1524)
				(type default)
			)
			(layer "F.SilkS")
		)
		(fp_line
			(start -0.67945 0.3048)
			(end -0.67945 -0.305054)
			(stroke
				(width 0.1)
				(type default)
			)
			(layer "F.Fab")
		)
		(fp_line
			(start -0.12065 0.3048)
			(end -0.67945 0.3048)
			(stroke
				(width 0.1)
				(type default)
			)
			(layer "F.Fab")
		)
		(fp_line
			(start 0.120396 0.3048)
			(end 0.120396 0.2794)
			(stroke
				(width 0.1)
				(type default)
			)
			(layer "F.Fab")
		)
		(fp_line
			(start 0.67945 0.3048)
			(end 0.120396 0.3048)
			(stroke
				(width 0.1)
				(type default)
			)
			(layer "F.Fab")
		)
		(fp_line
			(start -0.12065 0.2794)
			(end -0.12065 0.3048)
			(stroke
				(width 0.1)
				(type default)
			)
			(layer "F.Fab")
		)
		(fp_line
			(start 0.120396 0.2794)
			(end -0.12065 0.2794)
			(stroke
				(width 0.1)
				(type default)
			)
			(layer "F.Fab")
		)
		(fp_line
			(start -0.12065 -0.2794)
			(end 0.12065 -0.2794)
			(stroke
				(width 0.1)
				(type default)
			)
			(layer "F.Fab")
		)
		(fp_line
			(start 0.12065 -0.2794)
			(end 0.12065 -0.3048)
			(stroke
				(width 0.1)
				(type default)
			)
			(layer "F.Fab")
		)
		(fp_line
			(start 0.12065 -0.3048)
			(end 0.67945 -0.3048)
			(stroke
				(width 0.1)
				(type default)
			)
			(layer "F.Fab")
		)
		(fp_line
			(start 0.67945 -0.3048)
			(end 0.67945 0.3048)
			(stroke
				(width 0.1)
				(type default)
			)
			(layer "F.Fab")
		)
		(fp_line
			(start -0.67945 -0.305054)
			(end -0.12065 -0.305054)
			(stroke
				(width 0.1)
				(type default)
			)
			(layer "F.Fab")
		)
		(fp_line
			(start -0.12065 -0.305054)
			(end -0.12065 -0.2794)
			(stroke
				(width 0.1)
				(type default)
			)
			(layer "F.Fab")
		)
		(pad "1" smd circle
			(at -0.40005 0 270)
			(size 0 0)
			(layers "F.Cu" "F.Mask" "F.Paste")
			(net "P12V_AUX")
		)
		(pad "2" smd circle
			(at 0.40005 0 270)
			(size 0 0)
			(layers "F.Cu" "F.Mask" "F.Paste")
			(net "PVDD11_S3_P0_VINSEN")
		)
	)
)
